FILE_TYPE = CONNECTIVITY;
{Allegro Design Entry HDL 16.6-p007 (v16-6-112F) 10/10/2012}
"PAGE_NUMBER" = 135;
0"NC";
1"P3V3_STBY\g";
2"P3V3_STBY\g";
3"GND\g";
4"P3V3_STBY\g";
5"P3V3_STBY\g";
6"P3V3_STBY\g";
7"GND\g";
8"GND\g";
9"P3V3_STBY\g";
10"GND\g";
11"PU_KEY_CONN_PIN2_R";
12"TP_JUMPER_BLOCK_1_1";
13"TP_JUMPER_BLOCK_ 1_7";
14"RST_BMC_SRST_N";
15"FM_CPLD_UART_CH_LOCK_N";
16"FM_PCH_SATA_RAID_KEY_R";
17"FM_PCH_SATA_RAID_KEY";
18"FM_QAT_EN_N";
19"TP_JUMPER_BLOCK_1_2";
20"TP_JUMPER_BLOCK_1_8";
21"FM_IE_DISABLE_N";
22"FM_DIS_ADR_DLY";
%"P3V3_STBY"
"1","(200,2525)","0","mstr_symbols","I106";
;
VOLTAGE"3.3V"
HDL_POWER"P3V3_STBY"
SIZE"1B"
CDS_LIB"mstr_symbols"
BODY_TYPE"PLUMBING";
"G\NAC"1;
%"RES"
"2","(200,2225)","0","mstr_discrete","I107";
;
CDS_SEC"1"
CDS_LOCATION"R2P19"
ROOM"CPLD"
SEC_TYPE"0402"
BOM_COST"CPLD"
SEC"1"
CDS_LIB"mstr_discrete"
LOCATION"R2P19"
PART_NUMBER"G21796-016"
VALUE"10.0K"
TOLERANCE"1%"
PACK_TYPE"0402"
MATERIAL"CHIP"
WATTAGE"1/16W";
"A"
$PN"1"1;
"B"
$PN"2"22;
%"P3V3_STBY"
"1","(-2150,5025)","0","mstr_symbols","I111";
;
VOLTAGE"3.3V"
HDL_POWER"P3V3_STBY"
CDS_LIB"mstr_symbols"
SIZE"1B"
BODY_TYPE"PLUMBING";
"G\NAC"2;
%"RES"
"2","(-2150,4775)","0","mstr_discrete","I112";
;
ROOM"SB"
CDS_SEC"1"
$SEC"1"
CDS_LOCATION"R2N23"
CDS_LIB"mstr_discrete"
LOCATION"R2N23"
PART_NUMBER"G21796-016"
VALUE"10.0K"
TOLERANCE"1%"
PACK_TYPE"0402"
MATERIAL"CHIP"
WATTAGE"1/16W";
"A"
$PN"1"2;
"B"
$PN"2"18;
%"RES"
"2","(-2150,4325)","0","mstr_discrete","I113";
;
CDS_SEC"1"
ROOM"SB"
SEC_TYPE"0402"
SEC"1"
CDS_LOCATION"R2N24"
CDS_LIB"mstr_discrete"
MATERIAL"EMPTY"
LOCATION"R2N24"
PART_NUMBER"G21796-026"
VALUE"1.00K"
TOLERANCE"1%"
PACK_TYPE"0402"
WATTAGE"1/16W";
"A"
$PN"1"18;
"B"
$PN"2"3;
%"GND"
"1","(-2150,4125)","0","mstr_symbols","I114";
;
VOLTAGE"0.0V"
HDL_POWER"GND"
CDS_LIB"mstr_symbols"
BODY_TYPE"PLUMBING"
SIZE"1B";
"A\NAC"3;
%"P3V3_STBY"
"1","(-3875,5150)","0","mstr_symbols","I116";
;
VOLTAGE"3.3V"
HDL_POWER"P3V3_STBY"
SIZE"1B"
CDS_LIB"mstr_symbols"
BODY_TYPE"PLUMBING";
"G\NAC"4;
%"RES"
"1","(-3875,4900)","1","mstr_discrete","I117";
;
ROOM"SB"
CDS_LOCATION"R9A12"
$SEC"1"
CDS_SEC"1"
BOM_COST"SB"
CDS_LIB"mstr_discrete"
LOCATION"R9A12"
PART_NUMBER"G21796-112"
VALUE"2.21K"
TOLERANCE"1%"
PACK_TYPE"0402"
MATERIAL"CHIP"
WATTAGE"1/16W";
"B"
$PN"2"4;
"A"
$PN"1"16;
%"RES"
"1","(-3650,4500)","0","mstr_discrete","I118";
;
ROOM"SB"
$SEC"1"
CDS_SEC"1"
BOM_COST"SB"
CDS_LOCATION"R9A13"
CDS_LIB"mstr_discrete"
LOCATION"R9A13"
PART_NUMBER"G21796-074"
VALUE"33.2"
TOLERANCE"1%"
PACK_TYPE"0402"
MATERIAL"CHIP"
WATTAGE"1/16W";
"B"
$PN"2"17;
"A"
$PN"1"16;
%"P3V3_STBY"
"1","(-225,2525)","0","mstr_symbols","I119";
;
VOLTAGE"3.3V"
HDL_POWER"P3V3_STBY"
CDS_LIB"mstr_symbols"
SIZE"1B"
BODY_TYPE"PLUMBING";
"G\NAC"5;
%"RES"
"2","(-225,2250)","0","mstr_discrete","I120";
;
CDS_SEC"1"
ROOM"SB"
BOM_COST"SB"
SEC"1"
SEC_TYPE"0402"
CDS_LOCATION"R8D21"
CDS_LIB"mstr_discrete"
LOCATION"R8D21"
PART_NUMBER"G21796-026"
VALUE"1.00K"
TOLERANCE"1%"
PACK_TYPE"0402"
MATERIAL"CHIP"
WATTAGE"1/16W";
"A"
$PN"1"5;
"B"
$PN"2"21;
%"RES"
"2","(-1525,2250)","0","mstr_discrete","I121";
;
CDS_SEC"1"
ROOM"UART_MUX"
SEC_TYPE"0402"
BOM_COST"DEBUG"
SEC"1"
CDS_LOCATION"R7D30"
CDS_LIB"mstr_discrete"
LOCATION"R7D30"
PART_NUMBER"G21796-072"
VALUE"4.75K"
TOLERANCE"1%"
PACK_TYPE"0402"
MATERIAL"CHIP"
WATTAGE"1/16W";
"A"
$PN"1"6;
"B"
$PN"2"15;
%"P3V3_STBY"
"1","(-1525,2500)","0","mstr_symbols","I122";
;
VOLTAGE"3.3V"
HDL_POWER"P3V3_STBY"
SIZE"1B"
CDS_LIB"mstr_symbols"
BODY_TYPE"PLUMBING";
"G\NAC"6;
%"GND"
"1","(-300,1600)","0","mstr_symbols","I123";
;
VOLTAGE"0.0V"
HDL_POWER"GND"
SIZE"1B"
BODY_TYPE"PLUMBING"
CDS_LIB"mstr_symbols";
"A\NAC"7;
%"CONN12_C73564003"
"1","(-775,1900)","0","mstr_conn","I124";
;
CDS_SEC"1"
CDS_LOCATION"J8G2"
PACK_TYPE"PIP"
ROOM"SB"
SEC_TYPE"PIP"
SEC"1"
CDS_LIB"mstr_conn"
BOM_COST"SB"
LOCATION"J8G2"
PART_NUMBER"C73564-003"
MATERIAL"CONN";
"IO9"
$PN"9"15;
"IO11"
$PN"11"8;
"IO7"
$PN"7"13;
"IO3"
$PN"3"14;
"IO1"
$PN"1"12;
"IO5"
$PN"5"8;
"IO8"
$PN"8"20;
"IO10"
$PN"10"22;
"IO12"
$PN"12"7;
"IO6"
$PN"6"7;
"IO4"
$PN"4"21;
"IO2"
$PN"2"19;
%"GND"
"1","(-1250,1575)","0","mstr_symbols","I125";
;
VOLTAGE"0.0V"
HDL_POWER"GND"
CDS_LIB"mstr_symbols"
SIZE"1B"
BODY_TYPE"PLUMBING";
"A\NAC"8;
%"P3V3_STBY"
"1","(-4275,5150)","0","mstr_symbols","I128";
;
VOLTAGE"3.3V"
HDL_POWER"P3V3_STBY"
SIZE"1B"
CDS_LIB"mstr_symbols"
BODY_TYPE"PLUMBING";
"G\NAC"9;
%"RES"
"1","(-4275,4900)","1","mstr_discrete","I129";
;
ROOM"SB"
CDS_SEC"1"
$SEC"1"
CDS_LOCATION"R9A16"
BOM_COST"SB"
CDS_LIB"mstr_discrete"
LOCATION"R9A16"
PART_NUMBER"G21796-112"
VALUE"2.21K"
TOLERANCE"1%"
PACK_TYPE"0402"
MATERIAL"CHIP"
WATTAGE"1/16W";
"B"
$PN"2"9;
"A"
$PN"1"11;
%"GND"
"1","(-4850,4325)","0","mstr_symbols","I130";
;
VOLTAGE"0"
HDL_POWER"GND"
ROOM"WBG_HEADERS_BIOS"
CDS_LIB"mstr_symbols"
SIZE"1B"
BOM_COST"SB"
BODY_TYPE"PLUMBING";
"A\NAC"10;
%"CONN4_D42317002"
"1","(-5075,4600)","2","mstr_conn","I131";
;
PACK_TYPE"PIP"
ROOM"SB"
CDS_LOCATION"J9A1"
$SEC"1"
CDS_SEC"1"
BOM_COST"SB"
CDS_LIB"mstr_conn"
LOCATION"J9A1"
PART_NUMBER"D42317-002"
MATERIAL"CONN";
"IO4"
$PN"4"16;
"IO3"
$PN"3"10;
"IO2"
$PN"2"11;
"IO1"
$PN"1"10;
END.
